(kicad_pcb
	(version 20241229)
	(generator "pcbnew")
	(generator_version "9.0")
	(general
		(thickness 1.6296)
		(legacy_teardrops no)
	)
	(paper "A3")
	(title_block
		(title "Thunderbolt to 10GbE adapter")
		(date "2026-04-21")
		(rev "1.1.0")
		(company "Antmicro Ltd")
		(comment 1 "www.antmicro.com")
		(comment 9 "footprints 59-63 of 703")
	)
	(layers
		(0 "F.Cu" signal)
		(4 "In1.Cu" signal)
		(6 "In2.Cu" signal)
		(8 "In3.Cu" signal)
		(10 "In4.Cu" signal)
		(12 "In5.Cu" signal)
		(14 "In6.Cu" signal)
		(2 "B.Cu" signal)
		(9 "F.Adhes" user "F.Adhesive")
		(11 "B.Adhes" user "B.Adhesive")
		(13 "F.Paste" user)
		(15 "B.Paste" user)
		(5 "F.SilkS" user "F.Silkscreen")
		(7 "B.SilkS" user "B.Silkscreen")
		(1 "F.Mask" user)
		(3 "B.Mask" user)
		(17 "Dwgs.User" user "User.Drawings")
		(19 "Cmts.User" user "User.Comments")
		(21 "Eco1.User" user "User.Eco1")
		(23 "Eco2.User" user "User.Eco2")
		(25 "Edge.Cuts" user)
		(27 "Margin" user)
		(31 "F.CrtYd" user "F.Courtyard")
		(29 "B.CrtYd" user "B.Courtyard")
		(35 "F.Fab" user)
		(33 "B.Fab" user)
	)
	(footprint "antmicro-footprints:R_0402_1005Metric"
		(layer "F.Cu")
		(at 136.15 108.15 180)
		(descr "Resistor SMD 0402")
		(tags "resistor SMD 0402")
		(property "Reference" "R88"
			(at -16.549997 -17.25 180)
			(layer "F.SilkS")
			(effects
				(font
					(size 0.7 0.7)
					(thickness 0.15)
				)
			)
		)
		(property "Value" "R_100k_0402"
			(at -1.011843 1.772047 180)
			(layer "F.Fab")
			(effects
				(font
					(size 0.7 0.7)
					(thickness 0.15)
				)
				(justify left bottom)
			)
		)
		(property "Datasheet" "https://www.bourns.com/docs/product-datasheets/cr.pdf"
			(at 0 0 180)
			(layer "F.Fab")
			(hide yes)
			(effects
				(font
					(size 1.27 1.27)
					(thickness 0.15)
				)
			)
		)
		(property "Description" "SMD Chip Resistor, 100 kohm, ± 1%, 62.5 mW, 0402 [1005 Metric], Thick Film, General Purpose"
			(at 0 0 180)
			(layer "F.Fab")
			(hide yes)
			(effects
				(font
					(size 1.27 1.27)
					(thickness 0.15)
				)
			)
		)
		(property "MPN" "CR0402-FX-1003GLF"
			(at 0 0 180)
			(unlocked yes)
			(layer "F.Fab")
			(hide yes)
			(effects
				(font
					(size 1 1)
					(thickness 0.15)
				)
			)
		)
		(property "Manufacturer" "Bourns"
			(at 0 0 180)
			(unlocked yes)
			(layer "F.Fab")
			(hide yes)
			(effects
				(font
					(size 1 1)
					(thickness 0.15)
				)
			)
		)
		(property "License" "Apache-2.0"
			(at 0 0 180)
			(unlocked yes)
			(layer "F.Fab")
			(hide yes)
			(effects
				(font
					(size 1 1)
					(thickness 0.15)
				)
			)
		)
		(property "Author" "Antmicro"
			(at 0 0 180)
			(unlocked yes)
			(layer "F.Fab")
			(hide yes)
			(effects
				(font
					(size 1 1)
					(thickness 0.15)
				)
			)
		)
		(property "Val" "100k"
			(at 0 0 180)
			(unlocked yes)
			(layer "F.Fab")
			(hide yes)
			(effects
				(font
					(size 1 1)
					(thickness 0.15)
				)
			)
		)
		(property "Tolerance" "1%"
			(at 0 0 180)
			(unlocked yes)
			(layer "F.Fab")
			(hide yes)
			(effects
				(font
					(size 1 1)
					(thickness 0.15)
				)
			)
		)
		(sheetname "/X710 DCDC converters/")
		(sheetfile "DCDC_converters_X710.kicad_sch")
		(attr smd)
		(fp_rect
			(start -0.925 -0.47)
			(end 0.925 0.47)
			(stroke
				(width 0.05)
				(type default)
			)
			(fill no)
			(layer "F.CrtYd")
		)
		(fp_rect
			(start -0.5 -0.25)
			(end 0.5 0.25)
			(stroke
				(width 0.15)
				(type solid)
			)
			(fill no)
			(layer "F.Fab")
		)
		(fp_text user "Author: Antmicro"
			(at -0.95 4.169 180)
			(layer "F.Fab")
			(effects
				(font
					(size 0.7 0.7)
					(thickness 0.15)
				)
				(justify left bottom)
			)
		)
		(fp_text user "${REFERENCE}"
			(at -0.95 3.168 180)
			(layer "F.Fab")
			(effects
				(font
					(size 0.7 0.7)
					(thickness 0.15)
				)
				(justify left bottom)
			)
		)
		(fp_text user "License: Apache-2.0"
			(at -0.95 5.169 180)
			(layer "F.Fab")
			(effects
				(font
					(size 0.7 0.7)
					(thickness 0.15)
				)
				(justify left bottom)
			)
		)
		(pad "1" smd roundrect
			(at -0.48 0 180)
			(size 0.59 0.64)
			(layers "F.Cu" "F.Mask" "F.Paste")
			(roundrect_rratio 0.25)
			(net 379 "/X710 DCDC converters/VCCD_PG")
			(pintype "passive")
		)
		(pad "2" smd roundrect
			(at 0.48 0 180)
			(size 0.59 0.64)
			(layers "F.Cu" "F.Mask" "F.Paste")
			(roundrect_rratio 0.25)
			(net 83 "/X710 DCDC converters/VCCD_VCC")
			(pintype "passive")
		)
	)
	(footprint "antmicro-footprints:C_0603_1608Metric_EIA"
		(layer "F.Cu")
		(at 135.905001 99.774999 -90)
		(descr "Capacitor SMD 0603, IPC-7351 Density Level A")
		(tags "Capacitor 0603")
		(property "Reference" "C242"
			(at -9.274999 -37.344999 270)
			(layer "F.SilkS")
			(effects
				(font
					(size 0.7 0.7)
					(thickness 0.15)
				)
			)
		)
		(property "Value" "C_22u_16V_0603"
			(at -1.42757 1.770288 270)
			(layer "F.Fab")
			(effects
				(font
					(size 0.7 0.7)
					(thickness 0.15)
				)
				(justify left bottom)
			)
		)
		(property "Datasheet" "https://product.samsungsem.com/mlcc/CL10A226MO7JZN.do"
			(at 0 0 270)
			(layer "F.Fab")
			(hide yes)
			(effects
				(font
					(size 1.27 1.27)
					(thickness 0.15)
				)
			)
		)
		(property "Description" "SMD Multilayer Ceramic Capacitor"
			(at 0 0 270)
			(layer "F.Fab")
			(hide yes)
			(effects
				(font
					(size 1.27 1.27)
					(thickness 0.15)
				)
			)
		)
		(property "MPN" "CL10A226MO7JZNC"
			(at 0 0 270)
			(unlocked yes)
			(layer "F.Fab")
			(hide yes)
			(effects
				(font
					(size 1 1)
					(thickness 0.15)
				)
			)
		)
		(property "Manufacturer" "Samsung Electro-Mechanics"
			(at 0 0 270)
			(unlocked yes)
			(layer "F.Fab")
			(hide yes)
			(effects
				(font
					(size 1 1)
					(thickness 0.15)
				)
			)
		)
		(property "License" "Apache-2.0"
			(at 0 0 270)
			(unlocked yes)
			(layer "F.Fab")
			(hide yes)
			(effects
				(font
					(size 1 1)
					(thickness 0.15)
				)
			)
		)
		(property "Author" "Antmicro"
			(at 0 0 270)
			(unlocked yes)
			(layer "F.Fab")
			(hide yes)
			(effects
				(font
					(size 1 1)
					(thickness 0.15)
				)
			)
		)
		(property "Val" "22u"
			(at 0 0 270)
			(unlocked yes)
			(layer "F.Fab")
			(hide yes)
			(effects
				(font
					(size 1 1)
					(thickness 0.15)
				)
			)
		)
		(property "Voltage" "16V"
			(at 0 0 270)
			(unlocked yes)
			(layer "F.Fab")
			(hide yes)
			(effects
				(font
					(size 1 1)
					(thickness 0.15)
				)
			)
		)
		(property "Dielectric" ""
			(at 0 0 270)
			(unlocked yes)
			(layer "F.Fab")
			(hide yes)
			(effects
				(font
					(size 1 1)
					(thickness 0.15)
				)
			)
		)
		(sheetname "/X710-AT2 power/")
		(sheetfile "x710-at2-power.kicad_sch")
		(attr smd)
		(fp_line
			(start -0.15 0.55)
			(end 0.15 0.55)
			(stroke
				(width 0.15)
				(type solid)
			)
			(layer "F.SilkS")
		)
		(fp_line
			(start -0.15 -0.55)
			(end 0.15 -0.55)
			(stroke
				(width 0.15)
				(type solid)
			)
			(layer "F.SilkS")
		)
		(fp_rect
			(start -1.25 -0.65)
			(end 1.25 0.65)
			(stroke
				(width 0.05)
				(type solid)
			)
			(fill no)
			(layer "F.CrtYd")
		)
		(fp_rect
			(start -0.8 -0.45)
			(end 0.8 0.45)
			(stroke
				(width 0.15)
				(type solid)
			)
			(fill no)
			(layer "F.Fab")
		)
		(fp_text user "License: Apache-2.0"
			(at -1.682 5.895 270)
			(layer "F.Fab")
			(effects
				(font
					(size 0.7 0.7)
					(thickness 0.15)
				)
				(justify left bottom)
			)
		)
		(fp_text user "Author: Antmicro"
			(at -1.682 4.894 270)
			(layer "F.Fab")
			(effects
				(font
					(size 0.7 0.7)
					(thickness 0.15)
				)
				(justify left bottom)
			)
		)
		(fp_text user "${REFERENCE}"
			(at -1.682 3.895 270)
			(layer "F.Fab")
			(effects
				(font
					(size 0.7 0.7)
					(thickness 0.15)
				)
				(justify left bottom)
			)
		)
		(pad "1" smd roundrect
			(at -0.7 0 270)
			(size 0.8 1.1)
			(layers "F.Cu" "F.Mask" "F.Paste")
			(roundrect_rratio 0.2)
			(net 23 "GND")
			(pintype "passive")
		)
		(pad "2" smd roundrect
			(at 0.7 0 270)
			(size 0.8 1.1)
			(layers "F.Cu" "F.Mask" "F.Paste")
			(roundrect_rratio 0.2)
			(net 9 "VCCD")
			(pintype "passive")
		)
	)
	(footprint "antmicro-footprints:C_0402_1005Metric"
		(layer "F.Cu")
		(at 136.85 131.1 90)
		(descr "Capacitor SMD 0402")
		(tags "capacitor SMD 0402")
		(property "Reference" "C101"
			(at -0.170996 7.15 90)
			(layer "F.SilkS")
			(effects
				(font
					(size 0.7 0.7)
					(thickness 0.15)
				)
				(justify left bottom)
			)
		)
		(property "Value" "C_10u_0402"
			(at -1.022927 2.155213 90)
			(layer "F.Fab")
			(effects
				(font
					(size 0.7 0.7)
					(thickness 0.15)
				)
				(justify left bottom)
			)
		)
		(property "Datasheet" "https://www.yageo.com/en/Chart/Download/pdf/CC0402MRX5R5BB106"
			(at 0 0 90)
			(layer "F.Fab")
			(hide yes)
			(effects
				(font
					(size 1.27 1.27)
					(thickness 0.15)
				)
			)
		)
		(property "Description" "SMD Multilayer Ceramic Capacitor, 10 µF, 6.3 V, 0402 [1005 Metric], ± 20%, X5R, CC Series"
			(at 0 0 90)
			(layer "F.Fab")
			(hide yes)
			(effects
				(font
					(size 1.27 1.27)
					(thickness 0.15)
				)
			)
		)
		(property "MPN" "CC0402MRX5R5BB106"
			(at 0 0 90)
			(unlocked yes)
			(layer "F.Fab")
			(hide yes)
			(effects
				(font
					(size 1 1)
					(thickness 0.15)
				)
			)
		)
		(property "Manufacturer" "YAGEO"
			(at 0 0 90)
			(unlocked yes)
			(layer "F.Fab")
			(hide yes)
			(effects
				(font
					(size 1 1)
					(thickness 0.15)
				)
			)
		)
		(property "License" "Apache-2.0"
			(at 0 0 90)
			(unlocked yes)
			(layer "F.Fab")
			(hide yes)
			(effects
				(font
					(size 1 1)
					(thickness 0.15)
				)
			)
		)
		(property "Val" "10u"
			(at 0 0 90)
			(unlocked yes)
			(layer "F.Fab")
			(hide yes)
			(effects
				(font
					(size 1 1)
					(thickness 0.15)
				)
			)
		)
		(property "Voltage" ""
			(at 0 0 90)
			(unlocked yes)
			(layer "F.Fab")
			(hide yes)
			(effects
				(font
					(size 1 1)
					(thickness 0.15)
				)
			)
		)
		(property "Dielectric" ""
			(at 0 0 90)
			(unlocked yes)
			(layer "F.Fab")
			(hide yes)
			(effects
				(font
					(size 1 1)
					(thickness 0.15)
				)
			)
		)
		(property "Author" "Antmicro"
			(at 0 0 90)
			(unlocked yes)
			(layer "F.Fab")
			(hide yes)
			(effects
				(font
					(size 1 1)
					(thickness 0.15)
				)
			)
		)
		(sheetname "/TB Controller - Power/")
		(sheetfile "tb-power.kicad_sch")
		(attr smd)
		(fp_rect
			(start -0.925 -0.47)
			(end 0.925 0.47)
			(stroke
				(width 0.05)
				(type default)
			)
			(fill no)
			(layer "F.CrtYd")
		)
		(fp_line
			(start 0.504 -0.25)
			(end 0.504 0.248)
			(stroke
				(width 0.15)
				(type solid)
			)
			(layer "F.Fab")
		)
		(fp_line
			(start -0.494 -0.25)
			(end 0.504 -0.25)
			(stroke
				(width 0.15)
				(type solid)
			)
			(layer "F.Fab")
		)
		(fp_line
			(start 0.504 0.248)
			(end -0.494 0.248)
			(stroke
				(width 0.15)
				(type solid)
			)
			(layer "F.Fab")
		)
		(fp_line
			(start -0.494 0.248)
			(end -0.494 -0.25)
			(stroke
				(width 0.15)
				(type solid)
			)
			(layer "F.Fab")
		)
		(fp_text user "License: Apache-2.0"
			(at -0.939 5.799 90)
			(layer "F.Fab")
			(effects
				(font
					(size 0.7 0.7)
					(thickness 0.15)
				)
				(justify left bottom)
			)
		)
		(fp_text user "Author: Antmicro"
			(at -0.939 3.399 90)
			(layer "F.Fab")
			(effects
				(font
					(size 0.7 0.7)
					(thickness 0.15)
				)
				(justify left bottom)
			)
		)
		(fp_text user "${REFERENCE}"
			(at -0.939 4.599 90)
			(layer "F.Fab")
			(effects
				(font
					(size 0.7 0.7)
					(thickness 0.15)
				)
				(justify left bottom)
			)
		)
		(pad "1" smd roundrect
			(at -0.48 0 90)
			(size 0.59 0.64)
			(layers "F.Cu" "F.Mask" "F.Paste")
			(roundrect_rratio 0.25)
			(net 23 "GND")
			(pintype "passive")
		)
		(pad "2" smd roundrect
			(at 0.48 0 90)
			(size 0.59 0.64)
			(layers "F.Cu" "F.Mask" "F.Paste")
			(roundrect_rratio 0.25)
			(net 57 "+3V3_TB")
			(pintype "passive")
		)
	)
	(footprint "antmicro-footprints:C_0402_1005Metric"
		(layer "F.Cu")
		(at 124.75 134.75 90)
		(descr "Capacitor SMD 0402")
		(tags "capacitor SMD 0402")
		(property "Reference" "C33"
			(at -3.05 0.45 90)
			(layer "F.SilkS")
			(effects
				(font
					(size 0.7 0.7)
					(thickness 0.15)
				)
				(justify left bottom)
			)
		)
		(property "Value" "C_220n_0402"
			(at -1.022927 2.155213 90)
			(layer "F.Fab")
			(effects
				(font
					(size 0.7 0.7)
					(thickness 0.15)
				)
				(justify left bottom)
			)
		)
		(property "Datasheet" "https://www.yageo.com/en/Chart/Download/pdf/CC0402KRX5R6BB224"
			(at 0 0 90)
			(layer "F.Fab")
			(hide yes)
			(effects
				(font
					(size 1.27 1.27)
					(thickness 0.15)
				)
			)
		)
		(property "Description" "SMD Multilayer Ceramic Capacitor, 0.22 µF, 10 V, 0402 [1005 Metric], ± 10%, X5R, CC Series"
			(at 0 0 90)
			(layer "F.Fab")
			(hide yes)
			(effects
				(font
					(size 1.27 1.27)
					(thickness 0.15)
				)
			)
		)
		(property "MPN" "CC0402KRX5R6BB224"
			(at 0 0 90)
			(unlocked yes)
			(layer "F.Fab")
			(hide yes)
			(effects
				(font
					(size 1 1)
					(thickness 0.15)
				)
			)
		)
		(property "Manufacturer" "YAGEO"
			(at 0 0 90)
			(unlocked yes)
			(layer "F.Fab")
			(hide yes)
			(effects
				(font
					(size 1 1)
					(thickness 0.15)
				)
			)
		)
		(property "License" "Apache-2.0"
			(at 0 0 90)
			(unlocked yes)
			(layer "F.Fab")
			(hide yes)
			(effects
				(font
					(size 1 1)
					(thickness 0.15)
				)
			)
		)
		(property "Author" "Antmicro"
			(at 0 0 90)
			(unlocked yes)
			(layer "F.Fab")
			(hide yes)
			(effects
				(font
					(size 1 1)
					(thickness 0.15)
				)
			)
		)
		(property "Val" "220n"
			(at 0 0 90)
			(unlocked yes)
			(layer "F.Fab")
			(hide yes)
			(effects
				(font
					(size 1 1)
					(thickness 0.15)
				)
			)
		)
		(property "Voltage" ""
			(at 0 0 90)
			(unlocked yes)
			(layer "F.Fab")
			(hide yes)
			(effects
				(font
					(size 1 1)
					(thickness 0.15)
				)
			)
		)
		(property "Dielectric" ""
			(at 0 0 90)
			(unlocked yes)
			(layer "F.Fab")
			(hide yes)
			(effects
				(font
					(size 1 1)
					(thickness 0.15)
				)
			)
		)
		(sheetname "/TB Controller/")
		(sheetfile "tb.kicad_sch")
		(attr smd)
		(fp_rect
			(start -0.925 -0.47)
			(end 0.925 0.47)
			(stroke
				(width 0.05)
				(type default)
			)
			(fill no)
			(layer "F.CrtYd")
		)
		(fp_line
			(start 0.504 -0.25)
			(end 0.504 0.248)
			(stroke
				(width 0.15)
				(type solid)
			)
			(layer "F.Fab")
		)
		(fp_line
			(start -0.494 -0.25)
			(end 0.504 -0.25)
			(stroke
				(width 0.15)
				(type solid)
			)
			(layer "F.Fab")
		)
		(fp_line
			(start 0.504 0.248)
			(end -0.494 0.248)
			(stroke
				(width 0.15)
				(type solid)
			)
			(layer "F.Fab")
		)
		(fp_line
			(start -0.494 0.248)
			(end -0.494 -0.25)
			(stroke
				(width 0.15)
				(type solid)
			)
			(layer "F.Fab")
		)
		(fp_text user "Author: Antmicro"
			(at -0.939 3.399 90)
			(layer "F.Fab")
			(effects
				(font
					(size 0.7 0.7)
					(thickness 0.15)
				)
				(justify left bottom)
			)
		)
		(fp_text user "License: Apache-2.0"
			(at -0.939 5.799 90)
			(layer "F.Fab")
			(effects
				(font
					(size 0.7 0.7)
					(thickness 0.15)
				)
				(justify left bottom)
			)
		)
		(fp_text user "${REFERENCE}"
			(at -0.939 4.599 90)
			(layer "F.Fab")
			(effects
				(font
					(size 0.7 0.7)
					(thickness 0.15)
				)
				(justify left bottom)
			)
		)
		(pad "1" smd roundrect
			(at -0.48 0 90)
			(size 0.59 0.64)
			(layers "F.Cu" "F.Mask" "F.Paste")
			(roundrect_rratio 0.25)
			(net 308 "/PD and TB DC-DC/USB3.TX0_P")
			(pintype "passive")
		)
		(pad "2" smd roundrect
			(at 0.48 0 90)
			(size 0.59 0.64)
			(layers "F.Cu" "F.Mask" "F.Paste")
			(roundrect_rratio 0.25)
			(net 167 "/TB Controller/PA_TX0_P")
			(pintype "passive")
		)
	)
	(footprint "antmicro-footprints:R_0402_1005Metric"
		(layer "F.Cu")
		(at 148.4 128.2 -90)
		(descr "Resistor SMD 0402")
		(tags "resistor SMD 0402")
		(property "Reference" "R80"
			(at 3.2 -0.4 270)
			(layer "F.SilkS")
			(effects
				(font
					(size 0.7 0.7)
					(thickness 0.15)
				)
				(justify left bottom)
			)
		)
		(property "Value" "R_3k3_0402"
			(at -1.011843 1.772047 270)
			(layer "F.Fab")
			(effects
				(font
					(size 0.7 0.7)
					(thickness 0.15)
				)
				(justify left bottom)
			)
		)
		(property "Datasheet" "https://www.bourns.com/docs/product-datasheets/cr.pdf"
			(at 0 0 270)
			(layer "F.Fab")
			(hide yes)
			(effects
				(font
					(size 1.27 1.27)
					(thickness 0.15)
				)
			)
		)
		(property "Description" "SMD Chip Resistor, 3.3 kohm, ± 1%, 63 mW, 0402 [1005 Metric], Thick Film, General Purpose"
			(at 0 0 270)
			(layer "F.Fab")
			(hide yes)
			(effects
				(font
					(size 1.27 1.27)
					(thickness 0.15)
				)
			)
		)
		(property "MPN" "CR0402-FX-3301GLF"
			(at 0 0 270)
			(unlocked yes)
			(layer "F.Fab")
			(hide yes)
			(effects
				(font
					(size 1 1)
					(thickness 0.15)
				)
			)
		)
		(property "Manufacturer" "Bourns"
			(at 0 0 270)
			(unlocked yes)
			(layer "F.Fab")
			(hide yes)
			(effects
				(font
					(size 1 1)
					(thickness 0.15)
				)
			)
		)
		(property "License" "Apache-2.0"
			(at 0 0 270)
			(unlocked yes)
			(layer "F.Fab")
			(hide yes)
			(effects
				(font
					(size 1 1)
					(thickness 0.15)
				)
			)
		)
		(property "Val" "3k3"
			(at 0 0 270)
			(unlocked yes)
			(layer "F.Fab")
			(hide yes)
			(effects
				(font
					(size 1 1)
					(thickness 0.15)
				)
			)
		)
		(property "Tolerance" "1%"
			(at 0 0 270)
			(unlocked yes)
			(layer "F.Fab")
			(hide yes)
			(effects
				(font
					(size 1 1)
					(thickness 0.15)
				)
			)
		)
		(property "Author" "Antmicro"
			(at 0 0 270)
			(unlocked yes)
			(layer "F.Fab")
			(hide yes)
			(effects
				(font
					(size 1 1)
					(thickness 0.15)
				)
			)
		)
		(sheetname "/TB flash memory/")
		(sheetfile "flash-memory.kicad_sch")
		(attr smd)
		(fp_rect
			(start -0.925 -0.47)
			(end 0.925 0.47)
			(stroke
				(width 0.05)
				(type default)
			)
			(fill no)
			(layer "F.CrtYd")
		)
		(fp_rect
			(start -0.5 -0.25)
			(end 0.5 0.25)
			(stroke
				(width 0.15)
				(type solid)
			)
			(fill no)
			(layer "F.Fab")
		)
		(fp_text user "License: Apache-2.0"
			(at -0.95 5.169 270)
			(layer "F.Fab")
			(effects
				(font
					(size 0.7 0.7)
					(thickness 0.15)
				)
				(justify left bottom)
			)
		)
		(fp_text user "Author: Antmicro"
			(at -0.95 4.169 270)
			(layer "F.Fab")
			(effects
				(font
					(size 0.7 0.7)
					(thickness 0.15)
				)
				(justify left bottom)
			)
		)
		(fp_text user "${REFERENCE}"
			(at -0.95 3.168 270)
			(layer "F.Fab")
			(effects
				(font
					(size 0.7 0.7)
					(thickness 0.15)
				)
				(justify left bottom)
			)
		)
		(pad "1" smd roundrect
			(at -0.48 0 270)
			(size 0.59 0.64)
			(layers "F.Cu" "F.Mask" "F.Paste")
			(roundrect_rratio 0.25)
			(net 358 "/TB flash memory/FLASH_WP")
			(pintype "passive")
		)
		(pad "2" smd roundrect
			(at 0.48 0 270)
			(size 0.59 0.64)
			(layers "F.Cu" "F.Mask" "F.Paste")
			(roundrect_rratio 0.25)
			(net 57 "+3V3_TB")
			(pintype "passive")
		)
	)
)
